(kicad_pcb
	(version 20260206)
	(generator "pcbnew")
	(generator_version "10.0")
	(general
		(thickness 1.6)
		(legacy_teardrops no)
	)
	(paper "A4")
	(title_block
		(title "Bryce Canyon_R.DPB_16317-1_OCP.brd")
		(comment 1 "Bryce Canyon / footprints 207-214 of 2099")
	)
	(layers
		(0 "F.Cu" signal "TOP")
		(4 "In1.Cu" signal "L2GND")
		(6 "In2.Cu" signal "L3")
		(8 "In3.Cu" signal "L4VCC")
		(10 "In4.Cu" signal "L5VCC")
		(12 "In5.Cu" signal "L6")
		(14 "In6.Cu" signal "L7GND")
		(2 "B.Cu" signal "BOTTOM")
		(9 "F.Adhes" user "F.Adhesive")
		(11 "B.Adhes" user "B.Adhesive")
		(13 "F.Paste" user "Package Geometry/Pastemask Top")
		(15 "B.Paste" user "Package Geometry/Pastemask Bottom")
		(5 "F.SilkS" user "Ref Des/Silkscreen Top")
		(7 "B.SilkS" user "Ref Des/Silkscreen Bottom")
		(1 "F.Mask" user "Board Geometry/Soldermask Top")
		(3 "B.Mask" user "Board Geometry/Soldermask Bottom")
		(17 "Dwgs.User" user "User.Drawings")
		(19 "Cmts.User" user "User.Comments")
		(21 "Eco1.User" user "User.Eco1")
		(23 "Eco2.User" user "User.Eco2")
		(25 "Edge.Cuts" user "Board Geometry/Outline")
		(27 "Margin" user)
		(31 "F.CrtYd" user "Package Geometry/Place Bound Top")
		(29 "B.CrtYd" user "Package Geometry/Place Bound Bottom")
		(35 "F.Fab" user "Ref Des/Assembly Top")
		(33 "B.Fab" user "Ref Des/Assembly Bottom")
	)
	(footprint ""
		(layer "F.Cu")
		(at 32.463486 -245.219474 90)
		(property "Reference" "C496"
			(at 0 0 90)
			(layer "F.SilkS")
			(hide yes)
			(effects
				(font
					(size 1.27 1.27)
				)
			)
		)
		(property "Value" "SCD01U16V1KX-GP"
			(at -2.8321 -1.7399 90)
			(unlocked yes)
			(layer "F.Fab")
			(hide yes)
			(effects
				(font
					(size 1.016 1.016)
					(thickness 0.1524)
				)
			)
		)
		(property "Device Type" "C0201H13"
			(at -2.8321 -3.2639 90)
			(unlocked yes)
			(layer "F.Fab")
			(hide yes)
			(effects
				(font
					(size 1.016 1.016)
					(thickness 0.1524)
				)
			)
		)
		(duplicate_pad_numbers_are_jumpers no)
		(fp_rect
			(start -0.2794 0.6477)
			(end 0.2794 -0.6477)
			(stroke
				(width 0)
				(type default)
			)
			(fill no)
			(layer "F.CrtYd")
		)
		(fp_rect
			(start -0.2794 0.6477)
			(end 0.2794 -0.6477)
			(stroke
				(width 0)
				(type default)
			)
			(fill no)
			(layer "F.Fab")
		)
		(pad "1" smd custom
			(at 0 -0.2794 90)
			(size 0.0762 0.0762)
			(layers "F.Cu" "F.Mask" "F.Paste")
			(net "SAS_HDD_RX_N0")
			(options
				(clearance outline)
				(anchor circle)
			)
			(primitives
				(gr_poly
					(pts
						(arc
							(start 0.1524 -0.127)
							(mid 0.137521 -0.162921)
							(end 0.1016 -0.1778)
						)
						(arc
							(start -0.1016 -0.1778)
							(mid -0.137521 -0.162921)
							(end -0.1524 -0.127)
						)
						(arc
							(start -0.1524 0.127)
							(mid -0.137521 0.162921)
							(end -0.1016 0.1778)
						)
						(arc
							(start 0.1016 0.1778)
							(mid 0.137521 0.162921)
							(end 0.1524 0.127)
						)
					)
					(width 0)
					(fill yes)
				)
			)
		)
		(pad "2" smd custom
			(at 0 0.2794 90)
			(size 0.0762 0.0762)
			(layers "F.Cu" "F.Mask" "F.Paste")
			(net "PHY_SCC_B_TO_DRV_B_0_DN")
			(options
				(clearance outline)
				(anchor circle)
			)
			(primitives
				(gr_poly
					(pts
						(arc
							(start 0.1524 -0.127)
							(mid 0.137521 -0.162921)
							(end 0.1016 -0.1778)
						)
						(arc
							(start -0.1016 -0.1778)
							(mid -0.137521 -0.162921)
							(end -0.1524 -0.127)
						)
						(arc
							(start -0.1524 0.127)
							(mid -0.137521 0.162921)
							(end -0.1016 0.1778)
						)
						(arc
							(start 0.1016 0.1778)
							(mid 0.137521 0.162921)
							(end 0.1524 0.127)
						)
					)
					(width 0)
					(fill yes)
				)
			)
		)
	)
	(footprint ""
		(layer "F.Cu")
		(at 254.127 -230.886 180)
		(property "Reference" "R502"
			(at 0 0 180)
			(layer "F.SilkS")
			(hide yes)
			(effects
				(font
					(size 1.27 1.27)
				)
			)
		)
		(property "Value" "10KR2F-2-GP"
			(at 0.064008 -3.993896 180)
			(unlocked yes)
			(layer "F.Fab")
			(hide yes)
			(effects
				(font
					(size 1.016 1.016)
					(thickness 0.1524)
				)
			)
		)
		(property "Device Type" "R402H16"
			(at 0.064008 -5.517896 180)
			(unlocked yes)
			(layer "F.Fab")
			(hide yes)
			(effects
				(font
					(size 1.016 1.016)
					(thickness 0.1524)
				)
			)
		)
		(duplicate_pad_numbers_are_jumpers no)
		(fp_line
			(start 0.508 -0.9398)
			(end -0.508 -0.9398)
			(stroke
				(width 0.1524)
				(type default)
			)
			(layer "F.SilkS")
		)
		(fp_line
			(start -0.508 -0.9398)
			(end -0.508 0.9398)
			(stroke
				(width 0.1524)
				(type default)
			)
			(layer "F.SilkS")
		)
		(fp_rect
			(start -0.508 0.9398)
			(end 0.508 -0.9398)
			(stroke
				(width 0)
				(type default)
			)
			(fill no)
			(layer "F.CrtYd")
		)
		(fp_rect
			(start -0.508 0.9398)
			(end 0.508 -0.9398)
			(stroke
				(width 0)
				(type default)
			)
			(fill no)
			(layer "F.Fab")
		)
		(pad "1" smd custom
			(at 0 -0.4445 180)
			(size 0.1397 0.1397)
			(layers "F.Cu" "F.Mask" "F.Paste")
			(net "P5V_B_1")
			(options
				(clearance outline)
				(anchor circle)
			)
			(primitives
				(gr_poly
					(pts
						(arc
							(start -0.1778 -0.2794)
							(mid -0.249642 -0.249642)
							(end -0.2794 -0.1778)
						)
						(arc
							(start -0.2794 0.1778)
							(mid -0.249642 0.249642)
							(end -0.1778 0.2794)
						)
						(arc
							(start 0.1778 0.2794)
							(mid 0.249642 0.249642)
							(end 0.2794 0.1778)
						)
						(arc
							(start 0.2794 -0.1778)
							(mid 0.249642 -0.249642)
							(end 0.1778 -0.2794)
						)
					)
					(width 0)
					(fill yes)
				)
			)
		)
		(pad "2" smd custom
			(at 0 0.4445 180)
			(size 0.1397 0.1397)
			(layers "F.Cu" "F.Mask" "F.Paste")
			(net "SCC_FULL_PWR_EN_5V_R")
			(options
				(clearance outline)
				(anchor circle)
			)
			(primitives
				(gr_poly
					(pts
						(arc
							(start -0.1778 -0.2794)
							(mid -0.249642 -0.249642)
							(end -0.2794 -0.1778)
						)
						(arc
							(start -0.2794 0.1778)
							(mid -0.249642 0.249642)
							(end -0.1778 0.2794)
						)
						(arc
							(start 0.1778 0.2794)
							(mid 0.249642 0.249642)
							(end 0.2794 0.1778)
						)
						(arc
							(start 0.2794 -0.1778)
							(mid 0.249642 -0.249642)
							(end 0.1778 -0.2794)
						)
					)
					(width 0)
					(fill yes)
				)
			)
		)
	)
	(footprint ""
		(layer "F.Cu")
		(at 27.448002 -231.62895 -90)
		(property "Reference" "R1099"
			(at 0 0 270)
			(layer "F.SilkS")
			(hide yes)
			(effects
				(font
					(size 1.27 1.27)
				)
			)
		)
		(property "Value" "0R2J-2-GP"
			(at 0.064008 -3.993896 270)
			(unlocked yes)
			(layer "F.Fab")
			(hide yes)
			(effects
				(font
					(size 1.016 1.016)
					(thickness 0.1524)
				)
			)
		)
		(property "Device Type" "R402H16"
			(at 0.064008 -5.517896 270)
			(unlocked yes)
			(layer "F.Fab")
			(hide yes)
			(effects
				(font
					(size 1.016 1.016)
					(thickness 0.1524)
				)
			)
		)
		(duplicate_pad_numbers_are_jumpers no)
		(fp_line
			(start -0.508 -0.9398)
			(end -0.508 0.9398)
			(stroke
				(width 0.1524)
				(type default)
			)
			(layer "F.SilkS")
		)
		(fp_line
			(start 0.508 -0.9398)
			(end -0.508 -0.9398)
			(stroke
				(width 0.1524)
				(type default)
			)
			(layer "F.SilkS")
		)
		(fp_rect
			(start -0.508 0.9398)
			(end 0.508 -0.9398)
			(stroke
				(width 0)
				(type default)
			)
			(fill no)
			(layer "F.CrtYd")
		)
		(fp_rect
			(start -0.508 0.9398)
			(end 0.508 -0.9398)
			(stroke
				(width 0)
				(type default)
			)
			(fill no)
			(layer "F.Fab")
		)
		(pad "1" smd custom
			(at 0 -0.4445 270)
			(size 0.1397 0.1397)
			(layers "F.Cu" "F.Mask" "F.Paste")
			(net "P12V_B_PGOOD")
			(options
				(clearance outline)
				(anchor circle)
			)
			(primitives
				(gr_poly
					(pts
						(arc
							(start -0.1778 -0.2794)
							(mid -0.249642 -0.249642)
							(end -0.2794 -0.1778)
						)
						(arc
							(start -0.2794 0.1778)
							(mid -0.249642 0.249642)
							(end -0.1778 0.2794)
						)
						(arc
							(start 0.1778 0.2794)
							(mid 0.249642 0.249642)
							(end 0.2794 0.1778)
						)
						(arc
							(start 0.2794 -0.1778)
							(mid 0.249642 -0.249642)
							(end 0.1778 -0.2794)
						)
					)
					(width 0)
					(fill yes)
				)
			)
		)
		(pad "2" smd custom
			(at 0 0.4445 270)
			(size 0.1397 0.1397)
			(layers "F.Cu" "F.Mask" "F.Paste")
			(net "P5V_B_1_EN_R")
			(options
				(clearance outline)
				(anchor circle)
			)
			(primitives
				(gr_poly
					(pts
						(arc
							(start -0.1778 -0.2794)
							(mid -0.249642 -0.249642)
							(end -0.2794 -0.1778)
						)
						(arc
							(start -0.2794 0.1778)
							(mid -0.249642 0.249642)
							(end -0.1778 0.2794)
						)
						(arc
							(start 0.1778 0.2794)
							(mid 0.249642 0.249642)
							(end 0.2794 0.1778)
						)
						(arc
							(start 0.2794 -0.1778)
							(mid 0.249642 -0.249642)
							(end 0.1778 -0.2794)
						)
					)
					(width 0)
					(fill yes)
				)
			)
		)
	)
	(footprint ""
		(layer "F.Cu")
		(at 410.464 -99.187)
		(property "Reference" "R450"
			(at 0 0 0)
			(layer "F.SilkS")
			(hide yes)
			(effects
				(font
					(size 1.27 1.27)
				)
			)
		)
		(property "Value" "91R3F-1-GP"
			(at -0.0254 -2.5146 0)
			(unlocked yes)
			(layer "F.Fab")
			(hide yes)
			(effects
				(font
					(size 1.016 1.016)
					(thickness 0.1524)
				)
			)
		)
		(property "Device Type" "R603H22"
			(at -0.0254 -4.0386 0)
			(unlocked yes)
			(layer "F.Fab")
			(hide yes)
			(effects
				(font
					(size 1.016 1.016)
					(thickness 0.1524)
				)
			)
		)
		(duplicate_pad_numbers_are_jumpers no)
		(fp_line
			(start -0.4826 0)
			(end -0.2032 0)
			(stroke
				(width 0.2032)
				(type default)
			)
			(layer "F.SilkS")
		)
		(fp_line
			(start 0.2032 0)
			(end 0.4826 0)
			(stroke
				(width 0.2032)
				(type default)
			)
			(layer "F.SilkS")
		)
		(fp_rect
			(start -0.5842 1.3335)
			(end 0.5842 -1.3335)
			(stroke
				(width 0)
				(type default)
			)
			(fill no)
			(layer "F.CrtYd")
		)
		(fp_rect
			(start -0.5842 1.3335)
			(end 0.5842 -1.3335)
			(stroke
				(width 0)
				(type default)
			)
			(fill no)
			(layer "F.Fab")
		)
		(pad "1" smd custom
			(at 0 -0.762)
			(size 0.2159 0.2159)
			(layers "F.Cu" "F.Mask" "F.Paste")
			(net "P5V_B_4")
			(options
				(clearance outline)
				(anchor circle)
			)
			(primitives
				(gr_poly
					(pts
						(arc
							(start -0.3302 -0.4318)
							(mid -0.402042 -0.402042)
							(end -0.4318 -0.3302)
						)
						(arc
							(start -0.4318 0.3302)
							(mid -0.402042 0.402042)
							(end -0.3302 0.4318)
						)
						(arc
							(start 0.3302 0.4318)
							(mid 0.402042 0.402042)
							(end 0.4318 0.3302)
						)
						(arc
							(start 0.4318 -0.3302)
							(mid 0.402042 -0.402042)
							(end 0.3302 -0.4318)
						)
					)
					(width 0)
					(fill yes)
				)
			)
		)
		(pad "2" smd custom
			(at 0 0.762)
			(size 0.2159 0.2159)
			(layers "F.Cu" "F.Mask" "F.Paste")
			(net "DRV_ACT_21")
			(options
				(clearance outline)
				(anchor circle)
			)
			(primitives
				(gr_poly
					(pts
						(arc
							(start -0.3302 -0.4318)
							(mid -0.402042 -0.402042)
							(end -0.4318 -0.3302)
						)
						(arc
							(start -0.4318 0.3302)
							(mid -0.402042 0.402042)
							(end -0.3302 0.4318)
						)
						(arc
							(start 0.3302 0.4318)
							(mid 0.402042 0.402042)
							(end 0.4318 0.3302)
						)
						(arc
							(start 0.4318 -0.3302)
							(mid 0.402042 -0.402042)
							(end 0.3302 -0.4318)
						)
					)
					(width 0)
					(fill yes)
				)
			)
		)
	)
	(footprint ""
		(layer "F.Cu")
		(at 118.364 -33.274)
		(property "Reference" "R690"
			(at 0 0 0)
			(layer "F.SilkS")
			(hide yes)
			(effects
				(font
					(size 1.27 1.27)
				)
			)
		)
		(property "Value" "2R6F-GP"
			(at -0.0508 -4.8514 0)
			(unlocked yes)
			(layer "F.Fab")
			(hide yes)
			(effects
				(font
					(size 1.016 1.016)
					(thickness 0.1524)
				)
			)
		)
		(property "Device Type" "R1206H26"
			(at 0 -6.3754 0)
			(unlocked yes)
			(layer "F.Fab")
			(hide yes)
			(effects
				(font
					(size 1.016 1.016)
					(thickness 0.1524)
				)
			)
		)
		(duplicate_pad_numbers_are_jumpers no)
		(fp_line
			(start -1.016 -2.2352)
			(end 1.016 -2.2352)
			(stroke
				(width 0.1524)
				(type default)
			)
			(layer "F.SilkS")
		)
		(fp_line
			(start -1.016 2.2352)
			(end -1.016 -2.2352)
			(stroke
				(width 0.1524)
				(type default)
			)
			(layer "F.SilkS")
		)
		(fp_line
			(start 1.016 -2.2352)
			(end 1.016 2.2352)
			(stroke
				(width 0.1524)
				(type default)
			)
			(layer "F.SilkS")
		)
		(fp_line
			(start 1.016 2.2352)
			(end -1.016 2.2352)
			(stroke
				(width 0.1524)
				(type default)
			)
			(layer "F.SilkS")
		)
		(fp_rect
			(start -1.0922 2.3114)
			(end 1.0922 -2.3114)
			(stroke
				(width 0)
				(type default)
			)
			(fill no)
			(layer "F.CrtYd")
		)
		(fp_poly
			(pts
				(xy -1.0922 -2.3114) (xy 1.0922 -2.3114) (xy 1.0922 2.3114) (xy -1.0922 2.3114)
			)
			(stroke
				(width 0)
				(type default)
			)
			(fill no)
			(layer "F.Fab")
		)
		(pad "1" smd rect
			(at 0 -1.397)
			(size 1.651 1.27)
			(layers "F.Cu" "F.Mask" "F.Paste")
			(net "P5V_HDD27")
		)
		(pad "2" smd rect
			(at 0 1.397)
			(size 1.651 1.27)
			(layers "F.Cu" "F.Mask" "F.Paste")
			(net "5V_PRE_27")
		)
	)
	(footprint ""
		(layer "F.Cu")
		(at 228.1682 -302.6918 90)
		(property "Reference" "C649"
			(at 0 0 90)
			(layer "F.SilkS")
			(hide yes)
			(effects
				(font
					(size 1.27 1.27)
				)
			)
		)
		(property "Value" "SCD1U16V2KX-3GP"
			(at 1.1811 -2.7051 90)
			(unlocked yes)
			(layer "F.Fab")
			(hide yes)
			(effects
				(font
					(size 1.016 1.016)
					(thickness 0.1524)
				)
			)
		)
		(property "Device Type" "C402H22"
			(at 1.1811 -4.2291 90)
			(unlocked yes)
			(layer "F.Fab")
			(hide yes)
			(effects
				(font
					(size 1.016 1.016)
					(thickness 0.1524)
				)
			)
		)
		(duplicate_pad_numbers_are_jumpers no)
		(fp_rect
			(start -0.4318 0.9525)
			(end 0.4318 -0.9525)
			(stroke
				(width 0)
				(type default)
			)
			(fill no)
			(layer "F.CrtYd")
		)
		(fp_rect
			(start -0.4318 0.9525)
			(end 0.4318 -0.9525)
			(stroke
				(width 0)
				(type default)
			)
			(fill no)
			(layer "F.Fab")
		)
		(pad "1" smd custom
			(at 0 -0.4445 90)
			(size 0.1524 0.1524)
			(layers "F.Cu" "F.Mask" "F.Paste")
			(net "P3V3_IN")
			(options
				(clearance outline)
				(anchor circle)
			)
			(primitives
				(gr_poly
					(pts
						(arc
							(start 0.3048 -0.2032)
							(mid 0.275042 -0.275042)
							(end 0.2032 -0.3048)
						)
						(arc
							(start -0.2032 -0.3048)
							(mid -0.275042 -0.275042)
							(end -0.3048 -0.2032)
						)
						(arc
							(start -0.3048 0.2032)
							(mid -0.275042 0.275042)
							(end -0.2032 0.3048)
						)
						(arc
							(start 0.2032 0.3048)
							(mid 0.275042 0.275042)
							(end 0.3048 0.2032)
						)
					)
					(width 0)
					(fill yes)
				)
			)
		)
		(pad "2" smd custom
			(at 0 0.4445 90)
			(size 0.1524 0.1524)
			(layers "F.Cu" "F.Mask" "F.Paste")
			(net "GND")
			(options
				(clearance outline)
				(anchor circle)
			)
			(primitives
				(gr_poly
					(pts
						(arc
							(start 0.3048 -0.2032)
							(mid 0.275042 -0.275042)
							(end 0.2032 -0.3048)
						)
						(arc
							(start -0.2032 -0.3048)
							(mid -0.275042 -0.275042)
							(end -0.3048 -0.2032)
						)
						(arc
							(start -0.3048 0.2032)
							(mid -0.275042 0.275042)
							(end -0.2032 0.3048)
						)
						(arc
							(start 0.2032 0.3048)
							(mid 0.275042 0.275042)
							(end 0.3048 0.2032)
						)
					)
					(width 0)
					(fill yes)
				)
			)
		)
	)
	(footprint ""
		(layer "F.Cu")
		(at 384.9116 -31.6484)
		(property "Reference" "C453"
			(at 0 0 0)
			(layer "F.SilkS")
			(hide yes)
			(effects
				(font
					(size 1.27 1.27)
				)
			)
		)
		(property "Value" "SCD01U50V2KX-1GP"
			(at 1.1811 -2.7051 0)
			(unlocked yes)
			(layer "F.Fab")
			(hide yes)
			(effects
				(font
					(size 1.016 1.016)
					(thickness 0.1524)
				)
			)
		)
		(property "Device Type" "C402H22"
			(at 1.1811 -4.2291 0)
			(unlocked yes)
			(layer "F.Fab")
			(hide yes)
			(effects
				(font
					(size 1.016 1.016)
					(thickness 0.1524)
				)
			)
		)
		(duplicate_pad_numbers_are_jumpers no)
		(fp_rect
			(start -0.4318 0.9525)
			(end 0.4318 -0.9525)
			(stroke
				(width 0)
				(type default)
			)
			(fill no)
			(layer "F.CrtYd")
		)
		(fp_rect
			(start -0.4318 0.9525)
			(end 0.4318 -0.9525)
			(stroke
				(width 0)
				(type default)
			)
			(fill no)
			(layer "F.Fab")
		)
		(pad "1" smd custom
			(at 0 -0.4445)
			(size 0.1524 0.1524)
			(layers "F.Cu" "F.Mask" "F.Paste")
			(net "HDD_PRSNT_32")
			(options
				(clearance outline)
				(anchor circle)
			)
			(primitives
				(gr_poly
					(pts
						(arc
							(start 0.3048 -0.2032)
							(mid 0.275042 -0.275042)
							(end 0.2032 -0.3048)
						)
						(arc
							(start -0.2032 -0.3048)
							(mid -0.275042 -0.275042)
							(end -0.3048 -0.2032)
						)
						(arc
							(start -0.3048 0.2032)
							(mid -0.275042 0.275042)
							(end -0.2032 0.3048)
						)
						(arc
							(start 0.2032 0.3048)
							(mid 0.275042 0.275042)
							(end 0.3048 0.2032)
						)
					)
					(width 0)
					(fill yes)
				)
			)
		)
		(pad "2" smd custom
			(at 0 0.4445)
			(size 0.1524 0.1524)
			(layers "F.Cu" "F.Mask" "F.Paste")
			(net "GND")
			(options
				(clearance outline)
				(anchor circle)
			)
			(primitives
				(gr_poly
					(pts
						(arc
							(start 0.3048 -0.2032)
							(mid 0.275042 -0.275042)
							(end 0.2032 -0.3048)
						)
						(arc
							(start -0.2032 -0.3048)
							(mid -0.275042 -0.275042)
							(end -0.3048 -0.2032)
						)
						(arc
							(start -0.3048 0.2032)
							(mid -0.275042 0.275042)
							(end -0.2032 0.3048)
						)
						(arc
							(start 0.2032 0.3048)
							(mid 0.275042 0.275042)
							(end 0.3048 0.2032)
						)
					)
					(width 0)
					(fill yes)
				)
			)
		)
	)
	(footprint ""
		(layer "F.Cu")
		(at 304.519076 -340.812882 180)
		(property "Reference" "R99"
			(at 0 0 180)
			(layer "F.SilkS")
			(hide yes)
			(effects
				(font
					(size 1.27 1.27)
				)
			)
		)
		(property "Value" "4K7R2F-GP"
			(at 0.064008 -3.993896 180)
			(unlocked yes)
			(layer "F.Fab")
			(hide yes)
			(effects
				(font
					(size 1.016 1.016)
					(thickness 0.1524)
				)
			)
		)
		(property "Device Type" "R402H16"
			(at 0.064008 -5.517896 180)
			(unlocked yes)
			(layer "F.Fab")
			(hide yes)
			(effects
				(font
					(size 1.016 1.016)
					(thickness 0.1524)
				)
			)
		)
		(duplicate_pad_numbers_are_jumpers no)
		(fp_line
			(start 0.508 -0.9398)
			(end -0.508 -0.9398)
			(stroke
				(width 0.1524)
				(type default)
			)
			(layer "F.SilkS")
		)
		(fp_line
			(start -0.508 -0.9398)
			(end -0.508 0.9398)
			(stroke
				(width 0.1524)
				(type default)
			)
			(layer "F.SilkS")
		)
		(fp_rect
			(start -0.508 0.9398)
			(end 0.508 -0.9398)
			(stroke
				(width 0)
				(type default)
			)
			(fill no)
			(layer "F.CrtYd")
		)
		(fp_rect
			(start -0.508 0.9398)
			(end 0.508 -0.9398)
			(stroke
				(width 0)
				(type default)
			)
			(fill no)
			(layer "F.Fab")
		)
		(pad "1" smd custom
			(at 0 -0.4445 180)
			(size 0.1397 0.1397)
			(layers "F.Cu" "F.Mask" "F.Paste")
			(net "THERMHOT#_C")
			(options
				(clearance outline)
				(anchor circle)
			)
			(primitives
				(gr_poly
					(pts
						(arc
							(start -0.1778 -0.2794)
							(mid -0.249642 -0.249642)
							(end -0.2794 -0.1778)
						)
						(arc
							(start -0.2794 0.1778)
							(mid -0.249642 0.249642)
							(end -0.1778 0.2794)
						)
						(arc
							(start 0.1778 0.2794)
							(mid 0.249642 0.249642)
							(end 0.2794 0.1778)
						)
						(arc
							(start 0.2794 -0.1778)
							(mid 0.249642 -0.249642)
							(end 0.1778 -0.2794)
						)
					)
					(width 0)
					(fill yes)
				)
			)
		)
		(pad "2" smd custom
			(at 0 0.4445 180)
			(size 0.1397 0.1397)
			(layers "F.Cu" "F.Mask" "F.Paste")
			(net "GND")
			(options
				(clearance outline)
				(anchor circle)
			)
			(primitives
				(gr_poly
					(pts
						(arc
							(start -0.1778 -0.2794)
							(mid -0.249642 -0.249642)
							(end -0.2794 -0.1778)
						)
						(arc
							(start -0.2794 0.1778)
							(mid -0.249642 0.249642)
							(end -0.1778 0.2794)
						)
						(arc
							(start 0.1778 0.2794)
							(mid 0.249642 0.249642)
							(end 0.2794 0.1778)
						)
						(arc
							(start 0.2794 -0.1778)
							(mid 0.249642 -0.249642)
							(end 0.1778 -0.2794)
						)
					)
					(width 0)
					(fill yes)
				)
			)
		)
	)
)
